(kicad_pcb
	(version 20260206)
	(generator "pcbnew")
	(generator_version "10.0")
	(general
		(thickness 1.6)
		(legacy_teardrops no)
	)
	(paper "A4")
	(title_block
		(title "baseboard — 13948-1b.1110WZS1818.brd")
		(comment 1 "Honey Badger (Wiwynn) / footprints 2124-2134 of 2523")
	)
	(layers
		(0 "F.Cu" signal "TOP")
		(4 "In1.Cu" signal "L2GND")
		(6 "In2.Cu" signal "L3")
		(8 "In3.Cu" signal "L4VCC")
		(10 "In4.Cu" signal "L5VCC")
		(12 "In5.Cu" signal "L6")
		(14 "In6.Cu" signal "L7GND")
		(2 "B.Cu" signal "BOTTOM")
		(9 "F.Adhes" user "F.Adhesive")
		(11 "B.Adhes" user "B.Adhesive")
		(13 "F.Paste" user "Package Geometry/Pastemask Top")
		(15 "B.Paste" user "Package Geometry/Pastemask Bottom")
		(5 "F.SilkS" user "Ref Des/Silkscreen Top")
		(7 "B.SilkS" user "Ref Des/Silkscreen Bottom")
		(1 "F.Mask" user "Board Geometry/Soldermask Top")
		(3 "B.Mask" user "Board Geometry/Soldermask Bottom")
		(17 "Dwgs.User" user "User.Drawings")
		(19 "Cmts.User" user "User.Comments")
		(21 "Eco1.User" user "User.Eco1")
		(23 "Eco2.User" user "User.Eco2")
		(25 "Edge.Cuts" user "Board Geometry/Outline")
		(27 "Margin" user)
		(31 "F.CrtYd" user "Package Geometry/Place Bound Top")
		(29 "B.CrtYd" user "Package Geometry/Place Bound Bottom")
		(35 "F.Fab" user "Ref Des/Assembly Top")
		(33 "B.Fab" user "Ref Des/Assembly Bottom")
	)
	(footprint ""
		(layer "B.Cu")
		(at 307.975 -50.927 180)
		(property "Reference" "C278"
			(at 0 0 0)
			(layer "B.SilkS")
			(hide yes)
			(effects
				(font
					(size 1.27 1.27)
				)
				(justify mirror)
			)
		)
		(property "Value" "SC1U25V3KX-GP"
			(at 0 -2.8194 180)
			(unlocked yes)
			(layer "B.Fab")
			(hide yes)
			(effects
				(font
					(size 1.016 1.016)
					(thickness 0.1524)
				)
				(justify mirror)
			)
		)
		(property "Device Type" "C603H36"
			(at 0 -4.3434 180)
			(unlocked yes)
			(layer "B.Fab")
			(hide yes)
			(effects
				(font
					(size 1.016 1.016)
					(thickness 0.1524)
				)
				(justify mirror)
			)
		)
		(duplicate_pad_numbers_are_jumpers no)
		(fp_line
			(start -0.508 0)
			(end 0.508 0)
			(stroke
				(width 0.2032)
				(type default)
			)
			(layer "B.SilkS")
		)
		(fp_rect
			(start 0.5842 1.3335)
			(end -0.5842 -1.3335)
			(stroke
				(width 0)
				(type default)
			)
			(fill no)
			(layer "B.CrtYd")
		)
		(fp_rect
			(start 0.5842 1.3335)
			(end -0.5842 -1.3335)
			(stroke
				(width 0)
				(type default)
			)
			(fill no)
			(layer "B.Fab")
		)
		(pad "1" smd custom
			(at 0 -0.762)
			(size 0.2159 0.2159)
			(layers "B.Cu" "B.Mask" "B.Paste")
			(net "P12V")
			(options
				(clearance outline)
				(anchor circle)
			)
			(primitives
				(gr_poly
					(pts
						(arc
							(start -0.3302 0.4318)
							(mid -0.402042 0.402042)
							(end -0.4318 0.3302)
						)
						(arc
							(start -0.4318 -0.3302)
							(mid -0.402042 -0.402042)
							(end -0.3302 -0.4318)
						)
						(arc
							(start 0.3302 -0.4318)
							(mid 0.402042 -0.402042)
							(end 0.4318 -0.3302)
						)
						(arc
							(start 0.4318 0.3302)
							(mid 0.402042 0.402042)
							(end 0.3302 0.4318)
						)
					)
					(width 0)
					(fill yes)
				)
			)
		)
		(pad "2" smd custom
			(at 0 0.762)
			(size 0.2159 0.2159)
			(layers "B.Cu" "B.Mask" "B.Paste")
			(net "GND")
			(options
				(clearance outline)
				(anchor circle)
			)
			(primitives
				(gr_poly
					(pts
						(arc
							(start -0.3302 0.4318)
							(mid -0.402042 0.402042)
							(end -0.4318 0.3302)
						)
						(arc
							(start -0.4318 -0.3302)
							(mid -0.402042 -0.402042)
							(end -0.3302 -0.4318)
						)
						(arc
							(start 0.3302 -0.4318)
							(mid 0.402042 -0.402042)
							(end 0.4318 -0.3302)
						)
						(arc
							(start 0.4318 0.3302)
							(mid 0.402042 0.402042)
							(end 0.3302 0.4318)
						)
					)
					(width 0)
					(fill yes)
				)
			)
		)
	)
	(footprint ""
		(layer "B.Cu")
		(at 115.20297 -92.3798 180)
		(property "Reference" "SC1257"
			(at 0 0 0)
			(layer "B.SilkS")
			(hide yes)
			(effects
				(font
					(size 1.27 1.27)
				)
				(justify mirror)
			)
		)
		(property "Value" "SCD1U6D3V1KX-GP"
			(at 2.8321 -1.7399 180)
			(unlocked yes)
			(layer "B.Fab")
			(hide yes)
			(effects
				(font
					(size 1.016 1.016)
					(thickness 0.1524)
				)
				(justify mirror)
			)
		)
		(property "Device Type" "C0201H13"
			(at 2.8321 -3.2639 180)
			(unlocked yes)
			(layer "B.Fab")
			(hide yes)
			(effects
				(font
					(size 1.016 1.016)
					(thickness 0.1524)
				)
				(justify mirror)
			)
		)
		(duplicate_pad_numbers_are_jumpers no)
		(fp_rect
			(start 0.2794 0.6477)
			(end -0.2794 -0.6477)
			(stroke
				(width 0)
				(type default)
			)
			(fill no)
			(layer "B.CrtYd")
		)
		(fp_rect
			(start 0.2794 0.6477)
			(end -0.2794 -0.6477)
			(stroke
				(width 0)
				(type default)
			)
			(fill no)
			(layer "B.Fab")
		)
		(pad "1" smd custom
			(at 0 -0.2794)
			(size 0.0762 0.0762)
			(layers "B.Cu" "B.Mask" "B.Paste")
			(net "P0V9_E")
			(options
				(clearance outline)
				(anchor circle)
			)
			(primitives
				(gr_poly
					(pts
						(arc
							(start 0.1524 0.127)
							(mid 0.137521 0.162921)
							(end 0.1016 0.1778)
						)
						(arc
							(start -0.1016 0.1778)
							(mid -0.137521 0.162921)
							(end -0.1524 0.127)
						)
						(arc
							(start -0.1524 -0.127)
							(mid -0.137521 -0.162921)
							(end -0.1016 -0.1778)
						)
						(arc
							(start 0.1016 -0.1778)
							(mid 0.137521 -0.162921)
							(end 0.1524 -0.127)
						)
					)
					(width 0)
					(fill yes)
				)
			)
		)
		(pad "2" smd custom
			(at 0 0.2794)
			(size 0.0762 0.0762)
			(layers "B.Cu" "B.Mask" "B.Paste")
			(net "GND")
			(options
				(clearance outline)
				(anchor circle)
			)
			(primitives
				(gr_poly
					(pts
						(arc
							(start 0.1524 0.127)
							(mid 0.137521 0.162921)
							(end 0.1016 0.1778)
						)
						(arc
							(start -0.1016 0.1778)
							(mid -0.137521 0.162921)
							(end -0.1524 0.127)
						)
						(arc
							(start -0.1524 -0.127)
							(mid -0.137521 -0.162921)
							(end -0.1016 -0.1778)
						)
						(arc
							(start 0.1016 -0.1778)
							(mid 0.137521 -0.162921)
							(end 0.1524 -0.127)
						)
					)
					(width 0)
					(fill yes)
				)
			)
		)
	)
	(footprint ""
		(layer "B.Cu")
		(at 110.88497 -85.598)
		(property "Reference" "STP56"
			(at 0 0 0)
			(layer "B.SilkS")
			(hide yes)
			(effects
				(font
					(size 1.27 1.27)
				)
				(justify mirror)
			)
		)
		(property "Value" "TPAD28"
			(at -0.0127 -1.8034 0)
			(unlocked yes)
			(layer "B.Fab")
			(hide yes)
			(effects
				(font
					(size 1.016 1.016)
					(thickness 0.1524)
				)
				(justify mirror)
			)
		)
		(property "Device Type" "TPAD28"
			(at -0.0127 -3.3274 0)
			(unlocked yes)
			(layer "B.Fab")
			(hide yes)
			(effects
				(font
					(size 1.016 1.016)
					(thickness 0.1524)
				)
				(justify mirror)
			)
		)
		(duplicate_pad_numbers_are_jumpers no)
		(fp_poly
			(pts
				(arc
					(start 0.3556 0)
					(mid -0.3556 0)
					(end 0.3556 0)
				)
			)
			(stroke
				(width 0)
				(type default)
			)
			(fill no)
			(layer "B.CrtYd")
		)
		(fp_poly
			(pts
				(arc
					(start 0.6096 0)
					(mid -0.6096 0)
					(end 0.6096 0)
				)
			)
			(stroke
				(width 0)
				(type default)
			)
			(fill no)
			(layer "B.Fab")
		)
		(pad "1" smd circle
			(at 0 0 180)
			(size 0.7112 0.7112)
			(layers "B.Cu" "B.Mask" "B.Paste")
			(net "EXP_LED18")
		)
	)
	(footprint ""
		(layer "B.Cu")
		(at 115.83797 -81.661)
		(property "Reference" "STP105"
			(at 0 0 0)
			(layer "B.SilkS")
			(hide yes)
			(effects
				(font
					(size 1.27 1.27)
				)
				(justify mirror)
			)
		)
		(property "Value" "TPAD28"
			(at -0.0127 -1.8034 0)
			(unlocked yes)
			(layer "B.Fab")
			(hide yes)
			(effects
				(font
					(size 1.016 1.016)
					(thickness 0.1524)
				)
				(justify mirror)
			)
		)
		(property "Device Type" "TPAD28"
			(at -0.0127 -3.3274 0)
			(unlocked yes)
			(layer "B.Fab")
			(hide yes)
			(effects
				(font
					(size 1.016 1.016)
					(thickness 0.1524)
				)
				(justify mirror)
			)
		)
		(duplicate_pad_numbers_are_jumpers no)
		(fp_poly
			(pts
				(arc
					(start 0.3556 0)
					(mid -0.3556 0)
					(end 0.3556 0)
				)
			)
			(stroke
				(width 0)
				(type default)
			)
			(fill no)
			(layer "B.CrtYd")
		)
		(fp_poly
			(pts
				(arc
					(start 0.6096 0)
					(mid -0.6096 0)
					(end 0.6096 0)
				)
			)
			(stroke
				(width 0)
				(type default)
			)
			(fill no)
			(layer "B.Fab")
		)
		(pad "1" smd circle
			(at 0 0 180)
			(size 0.7112 0.7112)
			(layers "B.Cu" "B.Mask" "B.Paste")
			(net "TEST_MUX_38")
		)
	)
	(footprint ""
		(layer "B.Cu")
		(at 106.407966 -51.054 180)
		(property "Reference" "SC1017"
			(at 0 0 0)
			(layer "B.SilkS")
			(hide yes)
			(effects
				(font
					(size 1.27 1.27)
				)
				(justify mirror)
			)
		)
		(property "Value" "SC10U6D3V5KX-4GP"
			(at 0.0762 -6.1214 180)
			(unlocked yes)
			(layer "B.Fab")
			(hide yes)
			(effects
				(font
					(size 1.016 1.016)
					(thickness 0.1524)
				)
				(justify mirror)
			)
		)
		(property "Device Type" "C805H58"
			(at 0.0762 -8.1534 180)
			(unlocked yes)
			(layer "B.Fab")
			(hide yes)
			(effects
				(font
					(size 1.016 1.016)
					(thickness 0.1524)
				)
				(justify mirror)
			)
		)
		(duplicate_pad_numbers_are_jumpers no)
		(fp_line
			(start -0.635 0)
			(end 0.635 0)
			(stroke
				(width 0.508)
				(type default)
			)
			(layer "B.SilkS")
		)
		(fp_rect
			(start 0.9652 1.778)
			(end -0.9652 -1.778)
			(stroke
				(width 0)
				(type default)
			)
			(fill no)
			(layer "B.CrtYd")
		)
		(fp_poly
			(pts
				(xy 0.9652 -1.778) (xy -0.9652 -1.778) (xy -0.9652 1.778) (xy 0.9652 1.778)
			)
			(stroke
				(width 0)
				(type default)
			)
			(fill no)
			(layer "B.Fab")
		)
		(pad "1" smd rect
			(at 0 -0.9652)
			(size 1.397 1.143)
			(layers "B.Cu" "B.Mask" "B.Paste")
			(net "P0V955_C")
		)
		(pad "2" smd rect
			(at 0 0.9652)
			(size 1.397 1.143)
			(layers "B.Cu" "B.Mask" "B.Paste")
			(net "GND")
		)
	)
	(footprint ""
		(layer "B.Cu")
		(at 269.748 -31.623 -90)
		(property "Reference" "PR46"
			(at 0 0 90)
			(layer "B.SilkS")
			(hide yes)
			(effects
				(font
					(size 1.27 1.27)
				)
				(justify mirror)
			)
		)
		(property "Value" "3K9R2F-GP"
			(at -0.064008 -3.993896 270)
			(unlocked yes)
			(layer "B.Fab")
			(hide yes)
			(effects
				(font
					(size 1.016 1.016)
					(thickness 0.1524)
				)
				(justify mirror)
			)
		)
		(property "Device Type" "R402H16"
			(at -0.064008 -5.517896 270)
			(unlocked yes)
			(layer "B.Fab")
			(hide yes)
			(effects
				(font
					(size 1.016 1.016)
					(thickness 0.1524)
				)
				(justify mirror)
			)
		)
		(duplicate_pad_numbers_are_jumpers no)
		(fp_line
			(start -0.508 -0.9398)
			(end 0.508 -0.9398)
			(stroke
				(width 0.1524)
				(type default)
			)
			(layer "B.SilkS")
		)
		(fp_line
			(start 0.508 -0.9398)
			(end 0.508 0.9398)
			(stroke
				(width 0.1524)
				(type default)
			)
			(layer "B.SilkS")
		)
		(fp_rect
			(start 0.508 0.9398)
			(end -0.508 -0.9398)
			(stroke
				(width 0)
				(type default)
			)
			(fill no)
			(layer "B.CrtYd")
		)
		(fp_rect
			(start 0.508 0.9398)
			(end -0.508 -0.9398)
			(stroke
				(width 0)
				(type default)
			)
			(fill no)
			(layer "B.Fab")
		)
		(pad "1" smd custom
			(at 0 -0.4445 90)
			(size 0.1397 0.1397)
			(layers "B.Cu" "B.Mask" "B.Paste")
			(net "P1V8_STBY_LL")
			(options
				(clearance outline)
				(anchor circle)
			)
			(primitives
				(gr_poly
					(pts
						(arc
							(start -0.1778 0.2794)
							(mid -0.249642 0.249642)
							(end -0.2794 0.1778)
						)
						(arc
							(start -0.2794 -0.1778)
							(mid -0.249642 -0.249642)
							(end -0.1778 -0.2794)
						)
						(arc
							(start 0.1778 -0.2794)
							(mid 0.249642 -0.249642)
							(end 0.2794 -0.1778)
						)
						(arc
							(start 0.2794 0.1778)
							(mid 0.249642 0.249642)
							(end 0.1778 0.2794)
						)
					)
					(width 0)
					(fill yes)
				)
			)
		)
		(pad "2" smd custom
			(at 0 0.4445 90)
			(size 0.1397 0.1397)
			(layers "B.Cu" "B.Mask" "B.Paste")
			(net "P1V8_STBY_LL_R")
			(options
				(clearance outline)
				(anchor circle)
			)
			(primitives
				(gr_poly
					(pts
						(arc
							(start -0.1778 0.2794)
							(mid -0.249642 0.249642)
							(end -0.2794 0.1778)
						)
						(arc
							(start -0.2794 -0.1778)
							(mid -0.249642 -0.249642)
							(end -0.1778 -0.2794)
						)
						(arc
							(start 0.1778 -0.2794)
							(mid 0.249642 -0.249642)
							(end 0.2794 -0.1778)
						)
						(arc
							(start 0.2794 0.1778)
							(mid 0.249642 0.249642)
							(end 0.1778 0.2794)
						)
					)
					(width 0)
					(fill yes)
				)
			)
		)
	)
	(footprint ""
		(layer "B.Cu")
		(at 276.352 -160.02 90)
		(property "Reference" "R331"
			(at 0 0 90)
			(layer "B.SilkS")
			(hide yes)
			(effects
				(font
					(size 1.27 1.27)
				)
				(justify mirror)
			)
		)
		(property "Value" "0R2J-2-GP"
			(at -0.064008 -3.993896 90)
			(unlocked yes)
			(layer "B.Fab")
			(hide yes)
			(effects
				(font
					(size 1.016 1.016)
					(thickness 0.1524)
				)
				(justify mirror)
			)
		)
		(property "Device Type" "R402H16"
			(at -0.064008 -5.517896 90)
			(unlocked yes)
			(layer "B.Fab")
			(hide yes)
			(effects
				(font
					(size 1.016 1.016)
					(thickness 0.1524)
				)
				(justify mirror)
			)
		)
		(duplicate_pad_numbers_are_jumpers no)
		(fp_line
			(start 0.508 -0.9398)
			(end 0.508 0.9398)
			(stroke
				(width 0.1524)
				(type default)
			)
			(layer "B.SilkS")
		)
		(fp_line
			(start -0.508 -0.9398)
			(end 0.508 -0.9398)
			(stroke
				(width 0.1524)
				(type default)
			)
			(layer "B.SilkS")
		)
		(fp_rect
			(start 0.508 0.9398)
			(end -0.508 -0.9398)
			(stroke
				(width 0)
				(type default)
			)
			(fill no)
			(layer "B.CrtYd")
		)
		(fp_rect
			(start 0.508 0.9398)
			(end -0.508 -0.9398)
			(stroke
				(width 0)
				(type default)
			)
			(fill no)
			(layer "B.Fab")
		)
		(pad "1" smd custom
			(at 0 -0.4445 270)
			(size 0.1397 0.1397)
			(layers "B.Cu" "B.Mask" "B.Paste")
			(net "BMC_EN_0V955_C")
			(options
				(clearance outline)
				(anchor circle)
			)
			(primitives
				(gr_poly
					(pts
						(arc
							(start -0.1778 0.2794)
							(mid -0.249642 0.249642)
							(end -0.2794 0.1778)
						)
						(arc
							(start -0.2794 -0.1778)
							(mid -0.249642 -0.249642)
							(end -0.1778 -0.2794)
						)
						(arc
							(start 0.1778 -0.2794)
							(mid 0.249642 -0.249642)
							(end 0.2794 -0.1778)
						)
						(arc
							(start 0.2794 0.1778)
							(mid 0.249642 0.249642)
							(end 0.1778 0.2794)
						)
					)
					(width 0)
					(fill yes)
				)
			)
		)
		(pad "2" smd custom
			(at 0 0.4445 270)
			(size 0.1397 0.1397)
			(layers "B.Cu" "B.Mask" "B.Paste")
			(net "BMC_EN_0V955_R")
			(options
				(clearance outline)
				(anchor circle)
			)
			(primitives
				(gr_poly
					(pts
						(arc
							(start -0.1778 0.2794)
							(mid -0.249642 0.249642)
							(end -0.2794 0.1778)
						)
						(arc
							(start -0.2794 -0.1778)
							(mid -0.249642 -0.249642)
							(end -0.1778 -0.2794)
						)
						(arc
							(start 0.1778 -0.2794)
							(mid 0.249642 -0.249642)
							(end 0.2794 -0.1778)
						)
						(arc
							(start 0.2794 0.1778)
							(mid 0.249642 0.249642)
							(end 0.1778 0.2794)
						)
					)
					(width 0)
					(fill yes)
				)
			)
		)
	)
	(footprint ""
		(layer "B.Cu")
		(at 78.982062 -59.906408 -90)
		(property "Reference" "SC923"
			(at 0 0 90)
			(layer "B.SilkS")
			(hide yes)
			(effects
				(font
					(size 1.27 1.27)
				)
				(justify mirror)
			)
		)
		(property "Value" "SC22U6D3V5MX-2GP"
			(at 0.0762 -6.1214 270)
			(unlocked yes)
			(layer "B.Fab")
			(hide yes)
			(effects
				(font
					(size 1.016 1.016)
					(thickness 0.1524)
				)
				(justify mirror)
			)
		)
		(property "Device Type" "C805H58"
			(at 0.0762 -8.1534 270)
			(unlocked yes)
			(layer "B.Fab")
			(hide yes)
			(effects
				(font
					(size 1.016 1.016)
					(thickness 0.1524)
				)
				(justify mirror)
			)
		)
		(duplicate_pad_numbers_are_jumpers no)
		(fp_line
			(start -0.635 0)
			(end 0.635 0)
			(stroke
				(width 0.508)
				(type default)
			)
			(layer "B.SilkS")
		)
		(fp_rect
			(start 0.9652 1.778)
			(end -0.9652 -1.778)
			(stroke
				(width 0)
				(type default)
			)
			(fill no)
			(layer "B.CrtYd")
		)
		(fp_poly
			(pts
				(xy 0.9652 -1.778) (xy -0.9652 -1.778) (xy -0.9652 1.778) (xy 0.9652 1.778)
			)
			(stroke
				(width 0)
				(type default)
			)
			(fill no)
			(layer "B.Fab")
		)
		(pad "1" smd rect
			(at 0 -0.9652 90)
			(size 1.397 1.143)
			(layers "B.Cu" "B.Mask" "B.Paste")
			(net "VDDA_SAS_REF_CLK")
		)
		(pad "2" smd rect
			(at 0 0.9652 90)
			(size 1.397 1.143)
			(layers "B.Cu" "B.Mask" "B.Paste")
			(net "GND")
		)
	)
	(footprint ""
		(layer "B.Cu")
		(at 295.656 -167.64)
		(property "Reference" "TP156"
			(at 0 0 0)
			(layer "B.SilkS")
			(hide yes)
			(effects
				(font
					(size 1.27 1.27)
				)
				(justify mirror)
			)
		)
		(property "Value" "TPAD28"
			(at -0.0127 -1.8034 0)
			(unlocked yes)
			(layer "B.Fab")
			(hide yes)
			(effects
				(font
					(size 1.016 1.016)
					(thickness 0.1524)
				)
				(justify mirror)
			)
		)
		(property "Device Type" "TPAD28"
			(at -0.0127 -3.3274 0)
			(unlocked yes)
			(layer "B.Fab")
			(hide yes)
			(effects
				(font
					(size 1.016 1.016)
					(thickness 0.1524)
				)
				(justify mirror)
			)
		)
		(duplicate_pad_numbers_are_jumpers no)
		(fp_poly
			(pts
				(arc
					(start 0.3556 0)
					(mid -0.3556 0)
					(end 0.3556 0)
				)
			)
			(stroke
				(width 0)
				(type default)
			)
			(fill no)
			(layer "B.CrtYd")
		)
		(fp_poly
			(pts
				(arc
					(start 0.6096 0)
					(mid -0.6096 0)
					(end 0.6096 0)
				)
			)
			(stroke
				(width 0)
				(type default)
			)
			(fill no)
			(layer "B.Fab")
		)
		(pad "1" smd circle
			(at 0 0 180)
			(size 0.7112 0.7112)
			(layers "B.Cu" "B.Mask" "B.Paste")
			(net "TP_BMC_GPIOT7")
		)
	)
	(footprint ""
		(layer "B.Cu")
		(at 297.45432 -171.58462)
		(property "Reference" "TP97"
			(at 0 0 0)
			(layer "B.SilkS")
			(hide yes)
			(effects
				(font
					(size 1.27 1.27)
				)
				(justify mirror)
			)
		)
		(property "Value" "TPAD28"
			(at -0.0127 -1.8034 0)
			(unlocked yes)
			(layer "B.Fab")
			(hide yes)
			(effects
				(font
					(size 1.016 1.016)
					(thickness 0.1524)
				)
				(justify mirror)
			)
		)
		(property "Device Type" "TPAD28"
			(at -0.0127 -3.3274 0)
			(unlocked yes)
			(layer "B.Fab")
			(hide yes)
			(effects
				(font
					(size 1.016 1.016)
					(thickness 0.1524)
				)
				(justify mirror)
			)
		)
		(duplicate_pad_numbers_are_jumpers no)
		(fp_poly
			(pts
				(arc
					(start 0.3556 0)
					(mid -0.3556 0)
					(end 0.3556 0)
				)
			)
			(stroke
				(width 0)
				(type default)
			)
			(fill no)
			(layer "B.CrtYd")
		)
		(fp_poly
			(pts
				(arc
					(start 0.6096 0)
					(mid -0.6096 0)
					(end 0.6096 0)
				)
			)
			(stroke
				(width 0)
				(type default)
			)
			(fill no)
			(layer "B.Fab")
		)
		(pad "1" smd circle
			(at 0 0 180)
			(size 0.7112 0.7112)
			(layers "B.Cu" "B.Mask" "B.Paste")
			(net "TP_GPIOH7")
		)
	)
	(footprint ""
		(layer "B.Cu")
		(at 91.858084 -251.659136)
		(property "Reference" "TP79"
			(at 0 0 0)
			(layer "B.SilkS")
			(hide yes)
			(effects
				(font
					(size 1.27 1.27)
				)
				(justify mirror)
			)
		)
		(property "Value" "TPAD28"
			(at -0.0127 -1.8034 0)
			(unlocked yes)
			(layer "B.Fab")
			(hide yes)
			(effects
				(font
					(size 1.016 1.016)
					(thickness 0.1524)
				)
				(justify mirror)
			)
		)
		(property "Device Type" "TPAD28"
			(at -0.0127 -3.3274 0)
			(unlocked yes)
			(layer "B.Fab")
			(hide yes)
			(effects
				(font
					(size 1.016 1.016)
					(thickness 0.1524)
				)
				(justify mirror)
			)
		)
		(duplicate_pad_numbers_are_jumpers no)
		(fp_poly
			(pts
				(arc
					(start 0.3556 0)
					(mid -0.3556 0)
					(end 0.3556 0)
				)
			)
			(stroke
				(width 0)
				(type default)
			)
			(fill no)
			(layer "B.CrtYd")
		)
		(fp_poly
			(pts
				(arc
					(start 0.6096 0)
					(mid -0.6096 0)
					(end 0.6096 0)
				)
			)
			(stroke
				(width 0)
				(type default)
			)
			(fill no)
			(layer "B.Fab")
		)
		(pad "1" smd circle
			(at 0 0 180)
			(size 0.7112 0.7112)
			(layers "B.Cu" "B.Mask" "B.Paste")
			(net "SAS_I2C_D_BUF_SDA_R")
		)
	)
)
